(kicad_pcb
	(version 20260206)
	(generator "pcbnew")
	(generator_version "10.0")
	(general
		(thickness 1.6)
		(legacy_teardrops no)
	)
	(paper "A4")
	(title_block
		(title "v2-pdb — ms_pdb_v2.brd")
		(comment 1 "Open CloudServer (Microsoft) / footprint 332 of 348 (J16), pads 1-46 of 46")
	)
	(layers
		(0 "F.Cu" signal "TOP")
		(4 "In1.Cu" signal "GND")
		(6 "In2.Cu" signal "IN1")
		(8 "In3.Cu" signal "VCC")
		(10 "In4.Cu" signal "VCC1")
		(12 "In5.Cu" signal "IN2")
		(14 "In6.Cu" signal "GND1")
		(2 "B.Cu" signal "BOTTOM")
		(9 "F.Adhes" user "F.Adhesive")
		(11 "B.Adhes" user "B.Adhesive")
		(13 "F.Paste" user "Package Geometry/Pastemask Top")
		(15 "B.Paste" user "Package Geometry/Pastemask Bottom")
		(5 "F.SilkS" user "Ref Des/Silkscreen Top")
		(7 "B.SilkS" user "Ref Des/Silkscreen Bottom")
		(1 "F.Mask" user "Board Geometry/Soldermask Top")
		(3 "B.Mask" user "Board Geometry/Soldermask Bottom")
		(17 "Dwgs.User" user "User.Drawings")
		(19 "Cmts.User" user "User.Comments")
		(21 "Eco1.User" user "User.Eco1")
		(23 "Eco2.User" user "User.Eco2")
		(25 "Edge.Cuts" user "Board Geometry/Outline")
		(27 "Margin" user)
		(31 "F.CrtYd" user "Package Geometry/Place Bound Top")
		(29 "B.CrtYd" user "Package Geometry/Place Bound Bottom")
		(35 "F.Fab" user "Ref Des/Assembly Top")
		(33 "B.Fab" user "Ref Des/Assembly Bottom")
	)
	(footprint ""
		(layer "B.Cu")
		(at 44.03979 -408.31008 90)
		(property "Reference" "J16"
			(at 6.272784 -4.326636 0)
			(unlocked yes)
			(layer "B.SilkS")
			(effects
				(font
					(size 0.7874 0.5842)
					(thickness 0.1524)
				)
				(justify left mirror)
			)
		)
		(property "Value" ""
			(at 0 0 90)
			(layer "B.Fab")
			(effects
				(font
					(size 1.27 1.27)
				)
				(justify mirror)
			)
		)
		(duplicate_pad_numbers_are_jumpers no)
		(pad "" np_thru_hole circle
			(at -1.35001 -2.54)
			(size 2.5146 2.5146)
			(drill 2.5146)
			(layers "*.Cu" "*.Mask")
			(clearance 0.381)
			(thermal_gap 0.381)
		)
		(pad "" np_thru_hole circle
			(at 0 50.8)
			(size 2.5146 2.5146)
			(drill 2.5146)
			(layers "*.Cu" "*.Mask")
			(clearance 0.381)
			(thermal_gap 0.381)
		)
		(pad "P1" thru_hole rect
			(at 0 0)
			(size 1.1684 1.1684)
			(drill 0.762)
			(layers "*.Cu" "*.Mask")
			(remove_unused_layers no)
			(net "GND")
			(clearance 0.0508)
			(padstack
				(mode front_inner_back)
				(layer "Inner"
					(shape circle)
					(size 1.1684 1.1684)
					(clearance 0.0508)
				)
				(layer "B.Cu"
					(shape rect)
					(size 1.1684 1.1684)
					(thermal_gap 0.0508)
					(clearance 0.0508)
				)
			)
		)
		(pad "P2" thru_hole circle
			(at 0 2.54)
			(size 1.1684 1.1684)
			(drill 0.762)
			(layers "*.Cu" "*.Mask")
			(remove_unused_layers no)
			(net "GND")
			(clearance 0.0508)
			(thermal_gap 0.0508)
		)
		(pad "P3" thru_hole circle
			(at 0 5.08)
			(size 1.1684 1.1684)
			(drill 0.762)
			(layers "*.Cu" "*.Mask")
			(remove_unused_layers no)
			(net "GND")
			(clearance 0.0508)
			(thermal_gap 0.0508)
		)
		(pad "P4" thru_hole circle
			(at 0 7.62)
			(size 1.1684 1.1684)
			(drill 0.762)
			(layers "*.Cu" "*.Mask")
			(remove_unused_layers no)
			(net "GND")
			(clearance 0.0508)
			(thermal_gap 0.0508)
		)
		(pad "P5" thru_hole circle
			(at 0 10.16)
			(size 1.1684 1.1684)
			(drill 0.762)
			(layers "*.Cu" "*.Mask")
			(remove_unused_layers no)
			(net "GND")
			(clearance 0.0508)
			(thermal_gap 0.0508)
		)
		(pad "P6" thru_hole circle
			(at 0 12.7)
			(size 1.1684 1.1684)
			(drill 0.762)
			(layers "*.Cu" "*.Mask")
			(remove_unused_layers no)
			(net "GND")
			(clearance 0.0508)
			(thermal_gap 0.0508)
		)
		(pad "P7" thru_hole circle
			(at 0 15.24)
			(size 1.1684 1.1684)
			(drill 0.762)
			(layers "*.Cu" "*.Mask")
			(remove_unused_layers no)
			(net "GND")
			(clearance 0.0508)
			(thermal_gap 0.0508)
		)
		(pad "P8" thru_hole circle
			(at 0 17.78)
			(size 1.1684 1.1684)
			(drill 0.762)
			(layers "*.Cu" "*.Mask")
			(remove_unused_layers no)
			(net "GND")
			(clearance 0.0508)
			(thermal_gap 0.0508)
		)
		(pad "P9" thru_hole circle
			(at 0 20.32)
			(size 1.1684 1.1684)
			(drill 0.762)
			(layers "*.Cu" "*.Mask")
			(remove_unused_layers no)
			(net "P12V")
			(clearance 0.0508)
			(thermal_gap 0.0508)
		)
		(pad "P10" thru_hole circle
			(at 0 22.86)
			(size 1.1684 1.1684)
			(drill 0.762)
			(layers "*.Cu" "*.Mask")
			(remove_unused_layers no)
			(net "P12V")
			(clearance 0.0508)
			(thermal_gap 0.0508)
		)
		(pad "P11" thru_hole circle
			(at 0 25.4)
			(size 1.1684 1.1684)
			(drill 0.762)
			(layers "*.Cu" "*.Mask")
			(remove_unused_layers no)
			(net "P12V")
			(clearance 0.0508)
			(thermal_gap 0.0508)
		)
		(pad "P12" thru_hole circle
			(at 0 27.94)
			(size 1.1684 1.1684)
			(drill 0.762)
			(layers "*.Cu" "*.Mask")
			(remove_unused_layers no)
			(net "P12V")
			(clearance 0.0508)
			(thermal_gap 0.0508)
		)
		(pad "P13" thru_hole circle
			(at 0 30.48)
			(size 1.1684 1.1684)
			(drill 0.762)
			(layers "*.Cu" "*.Mask")
			(remove_unused_layers no)
			(net "P12V")
			(clearance 0.0508)
			(thermal_gap 0.0508)
		)
		(pad "P14" thru_hole circle
			(at 0 33.02)
			(size 1.1684 1.1684)
			(drill 0.762)
			(layers "*.Cu" "*.Mask")
			(remove_unused_layers no)
			(net "P12V")
			(clearance 0.0508)
			(thermal_gap 0.0508)
		)
		(pad "P15" thru_hole circle
			(at 0 35.56)
			(size 1.1684 1.1684)
			(drill 0.762)
			(layers "*.Cu" "*.Mask")
			(remove_unused_layers no)
			(net "P12V")
			(clearance 0.0508)
			(thermal_gap 0.0508)
		)
		(pad "P16" thru_hole circle
			(at 0 38.1)
			(size 1.1684 1.1684)
			(drill 0.762)
			(layers "*.Cu" "*.Mask")
			(remove_unused_layers no)
			(net "P12V")
			(clearance 0.0508)
			(thermal_gap 0.0508)
		)
		(pad "P17" thru_hole circle
			(at -2.70002 38.1)
			(size 1.1684 1.1684)
			(drill 0.762)
			(layers "*.Cu" "*.Mask")
			(remove_unused_layers no)
			(net "P12V")
			(clearance 0.0508)
			(thermal_gap 0.0508)
		)
		(pad "P18" thru_hole circle
			(at -2.70002 35.56)
			(size 1.1684 1.1684)
			(drill 0.762)
			(layers "*.Cu" "*.Mask")
			(remove_unused_layers no)
			(net "P12V")
			(clearance 0.0508)
			(thermal_gap 0.0508)
		)
		(pad "P19" thru_hole circle
			(at -2.70002 33.02)
			(size 1.1684 1.1684)
			(drill 0.762)
			(layers "*.Cu" "*.Mask")
			(remove_unused_layers no)
			(net "P12V")
			(clearance 0.0508)
			(thermal_gap 0.0508)
		)
		(pad "P20" thru_hole circle
			(at -2.70002 30.48)
			(size 1.1684 1.1684)
			(drill 0.762)
			(layers "*.Cu" "*.Mask")
			(remove_unused_layers no)
			(net "P12V")
			(clearance 0.0508)
			(thermal_gap 0.0508)
		)
		(pad "P21" thru_hole circle
			(at -2.70002 27.94)
			(size 1.1684 1.1684)
			(drill 0.762)
			(layers "*.Cu" "*.Mask")
			(remove_unused_layers no)
			(net "P12V")
			(clearance 0.0508)
			(thermal_gap 0.0508)
		)
		(pad "P22" thru_hole circle
			(at -2.70002 25.4)
			(size 1.1684 1.1684)
			(drill 0.762)
			(layers "*.Cu" "*.Mask")
			(remove_unused_layers no)
			(net "P12V")
			(clearance 0.0508)
			(thermal_gap 0.0508)
		)
		(pad "P23" thru_hole circle
			(at -2.70002 22.86)
			(size 1.1684 1.1684)
			(drill 0.762)
			(layers "*.Cu" "*.Mask")
			(remove_unused_layers no)
			(net "P12V")
			(clearance 0.0508)
			(thermal_gap 0.0508)
		)
		(pad "P24" thru_hole circle
			(at -2.70002 20.32)
			(size 1.1684 1.1684)
			(drill 0.762)
			(layers "*.Cu" "*.Mask")
			(remove_unused_layers no)
			(net "P12V")
			(clearance 0.0508)
			(thermal_gap 0.0508)
		)
		(pad "P25" thru_hole circle
			(at -2.70002 17.78)
			(size 1.1684 1.1684)
			(drill 0.762)
			(layers "*.Cu" "*.Mask")
			(remove_unused_layers no)
			(net "GND")
			(clearance 0.0508)
			(thermal_gap 0.0508)
		)
		(pad "P26" thru_hole circle
			(at -2.70002 15.24)
			(size 1.1684 1.1684)
			(drill 0.762)
			(layers "*.Cu" "*.Mask")
			(remove_unused_layers no)
			(net "GND")
			(clearance 0.0508)
			(thermal_gap 0.0508)
		)
		(pad "P27" thru_hole circle
			(at -2.70002 12.7)
			(size 1.1684 1.1684)
			(drill 0.762)
			(layers "*.Cu" "*.Mask")
			(remove_unused_layers no)
			(net "GND")
			(clearance 0.0508)
			(thermal_gap 0.0508)
		)
		(pad "P28" thru_hole circle
			(at -2.70002 10.16)
			(size 1.1684 1.1684)
			(drill 0.762)
			(layers "*.Cu" "*.Mask")
			(remove_unused_layers no)
			(net "GND")
			(clearance 0.0508)
			(thermal_gap 0.0508)
		)
		(pad "P29" thru_hole circle
			(at -2.70002 7.62)
			(size 1.1684 1.1684)
			(drill 0.762)
			(layers "*.Cu" "*.Mask")
			(remove_unused_layers no)
			(net "GND")
			(clearance 0.0508)
			(thermal_gap 0.0508)
		)
		(pad "P30" thru_hole circle
			(at -2.70002 5.08)
			(size 1.1684 1.1684)
			(drill 0.762)
			(layers "*.Cu" "*.Mask")
			(remove_unused_layers no)
			(net "GND")
			(clearance 0.0508)
			(thermal_gap 0.0508)
		)
		(pad "P31" thru_hole circle
			(at -2.70002 2.54)
			(size 1.1684 1.1684)
			(drill 0.762)
			(layers "*.Cu" "*.Mask")
			(remove_unused_layers no)
			(net "GND")
			(clearance 0.0508)
			(thermal_gap 0.0508)
		)
		(pad "P32" thru_hole circle
			(at -2.70002 0)
			(size 1.1684 1.1684)
			(drill 0.762)
			(layers "*.Cu" "*.Mask")
			(remove_unused_layers no)
			(net "GND")
			(clearance 0.0508)
			(thermal_gap 0.0508)
		)
		(pad "S1" thru_hole circle
			(at 0.55499 41.60012)
			(size 1.1684 1.1684)
			(drill 0.762)
			(layers "*.Cu" "*.Mask")
			(remove_unused_layers no)
			(net "T10_BLAD1_TXD")
			(clearance 0.0508)
			(thermal_gap 0.0508)
		)
		(pad "S2" thru_hole circle
			(at -0.71501 42.87012)
			(size 1.1684 1.1684)
			(drill 0.762)
			(layers "*.Cu" "*.Mask")
			(remove_unused_layers no)
			(net "T10_BLAD1_RXD")
			(clearance 0.0508)
			(thermal_gap 0.0508)
		)
		(pad "S3" thru_hole circle
			(at 0.55499 44.14012)
			(size 1.1684 1.1684)
			(drill 0.762)
			(layers "*.Cu" "*.Mask")
			(remove_unused_layers no)
			(net "T10_BLAD1_EN")
			(clearance 0.0508)
			(thermal_gap 0.0508)
		)
		(pad "S4" thru_hole circle
			(at -0.71501 45.41012)
			(size 1.1684 1.1684)
			(drill 0.762)
			(layers "*.Cu" "*.Mask")
			(remove_unused_layers no)
			(net "B19_PSU_ALERT_N")
			(clearance 0.0508)
			(thermal_gap 0.0508)
		)
		(pad "S5" thru_hole circle
			(at 0.55499 46.68012)
			(size 1.1684 1.1684)
			(drill 0.762)
			(layers "*.Cu" "*.Mask")
			(remove_unused_layers no)
			(net "T10_BLAD2_TXD")
			(clearance 0.0508)
			(thermal_gap 0.0508)
		)
		(pad "S6" thru_hole circle
			(at -0.71501 47.95012)
			(size 1.1684 1.1684)
			(drill 0.762)
			(layers "*.Cu" "*.Mask")
			(remove_unused_layers no)
			(net "T10_BLAD2_RXD")
			(clearance 0.0508)
			(thermal_gap 0.0508)
		)
		(pad "S7" thru_hole circle
			(at -3.25501 47.95012)
			(size 1.1684 1.1684)
			(drill 0.762)
			(layers "*.Cu" "*.Mask")
			(remove_unused_layers no)
			(net "T10_BLAD4_RXD")
			(clearance 0.0508)
			(thermal_gap 0.0508)
		)
		(pad "S8" thru_hole circle
			(at -1.98501 46.68012)
			(size 1.1684 1.1684)
			(drill 0.762)
			(layers "*.Cu" "*.Mask")
			(remove_unused_layers no)
			(net "T10_BLAD4_TXD")
			(clearance 0.0508)
			(thermal_gap 0.0508)
		)
		(pad "S9" thru_hole circle
			(at -3.25501 45.41012)
			(size 1.1684 1.1684)
			(drill 0.762)
			(layers "*.Cu" "*.Mask")
			(remove_unused_layers no)
			(net "B20_PSU_ALERT_N")
			(clearance 0.0508)
			(thermal_gap 0.0508)
		)
		(pad "S10" thru_hole circle
			(at -1.98501 44.14012)
			(size 1.1684 1.1684)
			(drill 0.762)
			(layers "*.Cu" "*.Mask")
			(remove_unused_layers no)
			(net "T10_BLAD3_EN")
			(clearance 0.0508)
			(thermal_gap 0.0508)
		)
		(pad "S11" thru_hole circle
			(at -3.25501 42.87012)
			(size 1.1684 1.1684)
			(drill 0.762)
			(layers "*.Cu" "*.Mask")
			(remove_unused_layers no)
			(net "T10_BLAD3_RXD")
			(clearance 0.0508)
			(thermal_gap 0.0508)
		)
		(pad "S12" thru_hole circle
			(at -1.98501 41.60012)
			(size 1.1684 1.1684)
			(drill 0.762)
			(layers "*.Cu" "*.Mask")
			(remove_unused_layers no)
			(net "T10_BLAD3_TXD")
			(clearance 0.0508)
			(thermal_gap 0.0508)
		)
	)
)
